(kicad_pcb
	(version 20260206)
	(generator "pcbnew")
	(generator_version "10.0")
	(general
		(thickness 1.6)
		(legacy_teardrops no)
	)
	(paper "A4")
	(title_block
		(title "04192023_DAF0TMB3IC0_F0TG_MB_C_brd_V02_OCP.brd")
		(comment 1 "Grand Teton / footprints 6303-6311 of 8354")
	)
	(layers
		(0 "F.Cu" signal "TOP")
		(4 "In1.Cu" signal "GND")
		(6 "In2.Cu" signal "IN1")
		(8 "In3.Cu" signal "GND1")
		(10 "In4.Cu" signal "IN2")
		(12 "In5.Cu" signal "GND2")
		(14 "In6.Cu" signal "IN3")
		(16 "In7.Cu" signal "GND3")
		(18 "In8.Cu" signal "VCC")
		(20 "In9.Cu" signal "VCC1")
		(22 "In10.Cu" signal "GND4")
		(24 "In11.Cu" signal "IN4")
		(26 "In12.Cu" signal "GND5")
		(28 "In13.Cu" signal "IN5")
		(30 "In14.Cu" signal "GND6")
		(32 "In15.Cu" signal "IN6")
		(34 "In16.Cu" signal "GND7")
		(2 "B.Cu" signal "BOTTOM")
		(9 "F.Adhes" user "F.Adhesive")
		(11 "B.Adhes" user "B.Adhesive")
		(13 "F.Paste" user "Package Geometry/Pastemask Top")
		(15 "B.Paste" user "Package Geometry/Pastemask Bottom")
		(5 "F.SilkS" user "Ref Des/Silkscreen Top")
		(7 "B.SilkS" user "Ref Des/Silkscreen Bottom")
		(1 "F.Mask" user "Board Geometry/Soldermask Top")
		(3 "B.Mask" user "Board Geometry/Soldermask Bottom")
		(17 "Dwgs.User" user "User.Drawings")
		(19 "Cmts.User" user "User.Comments")
		(21 "Eco1.User" user "User.Eco1")
		(23 "Eco2.User" user "User.Eco2")
		(25 "Edge.Cuts" user "Board Geometry/Outline")
		(27 "Margin" user)
		(31 "F.CrtYd" user "Package Geometry/Place Bound Top")
		(29 "B.CrtYd" user "Package Geometry/Place Bound Bottom")
		(35 "F.Fab" user "Ref Des/Assembly Top")
		(33 "B.Fab" user "Ref Des/Assembly Bottom")
	)
	(footprint ""
		(layer "B.Cu")
		(at 401.359116 -185.63336 90)
		(property "Reference" "PC602_1"
			(at 0 0 90)
			(layer "B.SilkS")
			(hide yes)
			(effects
				(font
					(size 1.27 1.27)
				)
				(justify mirror)
			)
		)
		(property "Value" ""
			(at 0 0 90)
			(layer "B.Fab")
			(effects
				(font
					(size 1.27 1.27)
				)
				(justify mirror)
			)
		)
		(duplicate_pad_numbers_are_jumpers no)
		(fp_line
			(start 1.524 -0.762)
			(end -1.524 -0.762)
			(stroke
				(width 0.1524)
				(type default)
			)
			(layer "B.SilkS")
		)
		(fp_line
			(start -1.524 -0.762)
			(end -1.524 0.762)
			(stroke
				(width 0.1524)
				(type default)
			)
			(layer "B.SilkS")
		)
		(fp_line
			(start 1.524 0.762)
			(end 1.524 -0.762)
			(stroke
				(width 0.1524)
				(type default)
			)
			(layer "B.SilkS")
		)
		(fp_line
			(start -1.524 0.762)
			(end 1.524 0.762)
			(stroke
				(width 0.1524)
				(type default)
			)
			(layer "B.SilkS")
		)
		(fp_line
			(start 1.1049 -0.724916)
			(end 1.1049 0.724916)
			(stroke
				(width 0.1)
				(type default)
			)
			(layer "B.Fab")
		)
		(fp_line
			(start -1.1049 -0.724916)
			(end 1.1049 -0.724916)
			(stroke
				(width 0.1)
				(type default)
			)
			(layer "B.Fab")
		)
		(fp_line
			(start 1.1049 0.724916)
			(end -1.1049 0.724916)
			(stroke
				(width 0.1)
				(type default)
			)
			(layer "B.Fab")
		)
		(fp_line
			(start -1.1049 0.724916)
			(end -1.1049 -0.724916)
			(stroke
				(width 0.1)
				(type default)
			)
			(layer "B.Fab")
		)
		(pad "1" smd rect
			(at 0.889 0 90)
			(size 1.016 1.27)
			(layers "B.Cu" "B.Mask" "B.Paste")
			(net "PVDDCR_SOC_P0")
		)
		(pad "2" smd rect
			(at -0.889 0 90)
			(size 1.016 1.27)
			(layers "B.Cu" "B.Mask" "B.Paste")
			(net "GND")
		)
	)
	(footprint ""
		(layer "B.Cu")
		(at 119.801386 -249.368564)
		(property "Reference" "C2345"
			(at 0 0 0)
			(layer "B.SilkS")
			(hide yes)
			(effects
				(font
					(size 1.27 1.27)
				)
				(justify mirror)
			)
		)
		(property "Value" ""
			(at 0 0 0)
			(layer "B.Fab")
			(effects
				(font
					(size 1.27 1.27)
				)
				(justify mirror)
			)
		)
		(duplicate_pad_numbers_are_jumpers no)
		(fp_line
			(start -0.7874 -0.4064)
			(end -0.7874 0.4064)
			(stroke
				(width 0.1524)
				(type default)
			)
			(layer "B.SilkS")
		)
		(fp_line
			(start -0.7874 0.4064)
			(end 0.7874 0.4064)
			(stroke
				(width 0.1524)
				(type default)
			)
			(layer "B.SilkS")
		)
		(fp_line
			(start 0.7874 -0.4064)
			(end -0.7874 -0.4064)
			(stroke
				(width 0.1524)
				(type default)
			)
			(layer "B.SilkS")
		)
		(fp_line
			(start 0.7874 0.4064)
			(end 0.7874 -0.4064)
			(stroke
				(width 0.1524)
				(type default)
			)
			(layer "B.SilkS")
		)
		(fp_line
			(start -0.67945 -0.3048)
			(end -0.67945 0.3048)
			(stroke
				(width 0.1)
				(type default)
			)
			(layer "B.Fab")
		)
		(fp_line
			(start -0.67945 0.3048)
			(end -0.120396 0.3048)
			(stroke
				(width 0.1)
				(type default)
			)
			(layer "B.Fab")
		)
		(fp_line
			(start -0.12065 -0.3048)
			(end -0.67945 -0.3048)
			(stroke
				(width 0.1)
				(type default)
			)
			(layer "B.Fab")
		)
		(fp_line
			(start -0.12065 -0.2794)
			(end -0.12065 -0.3048)
			(stroke
				(width 0.1)
				(type default)
			)
			(layer "B.Fab")
		)
		(fp_line
			(start -0.120396 0.2794)
			(end 0.12065 0.2794)
			(stroke
				(width 0.1)
				(type default)
			)
			(layer "B.Fab")
		)
		(fp_line
			(start -0.120396 0.3048)
			(end -0.120396 0.2794)
			(stroke
				(width 0.1)
				(type default)
			)
			(layer "B.Fab")
		)
		(fp_line
			(start 0.12065 -0.305054)
			(end 0.12065 -0.2794)
			(stroke
				(width 0.1)
				(type default)
			)
			(layer "B.Fab")
		)
		(fp_line
			(start 0.12065 -0.2794)
			(end -0.12065 -0.2794)
			(stroke
				(width 0.1)
				(type default)
			)
			(layer "B.Fab")
		)
		(fp_line
			(start 0.12065 0.2794)
			(end 0.12065 0.3048)
			(stroke
				(width 0.1)
				(type default)
			)
			(layer "B.Fab")
		)
		(fp_line
			(start 0.12065 0.3048)
			(end 0.67945 0.3048)
			(stroke
				(width 0.1)
				(type default)
			)
			(layer "B.Fab")
		)
		(fp_line
			(start 0.67945 -0.305054)
			(end 0.12065 -0.305054)
			(stroke
				(width 0.1)
				(type default)
			)
			(layer "B.Fab")
		)
		(fp_line
			(start 0.67945 0.3048)
			(end 0.67945 -0.305054)
			(stroke
				(width 0.1)
				(type default)
			)
			(layer "B.Fab")
		)
		(pad "1" smd circle
			(at 0.40005 0 180)
			(size 0 0)
			(layers "B.Cu" "B.Mask" "B.Paste")
			(net "PVDDCR_CPU0_P1")
		)
		(pad "2" smd circle
			(at -0.40005 0 180)
			(size 0 0)
			(layers "B.Cu" "B.Mask" "B.Paste")
			(net "GND")
		)
	)
	(footprint ""
		(layer "B.Cu")
		(at 284.82417 -346.784168 90)
		(property "Reference" "PC181_3"
			(at 0 0 90)
			(layer "B.SilkS")
			(hide yes)
			(effects
				(font
					(size 1.27 1.27)
				)
				(justify mirror)
			)
		)
		(property "Value" ""
			(at 0 0 90)
			(layer "B.Fab")
			(effects
				(font
					(size 1.27 1.27)
				)
				(justify mirror)
			)
		)
		(duplicate_pad_numbers_are_jumpers no)
		(fp_line
			(start 1.524 -0.762)
			(end -1.524 -0.762)
			(stroke
				(width 0.1524)
				(type default)
			)
			(layer "B.SilkS")
		)
		(fp_line
			(start -1.524 -0.762)
			(end -1.524 0.762)
			(stroke
				(width 0.1524)
				(type default)
			)
			(layer "B.SilkS")
		)
		(fp_line
			(start 1.524 0.762)
			(end 1.524 -0.762)
			(stroke
				(width 0.1524)
				(type default)
			)
			(layer "B.SilkS")
		)
		(fp_line
			(start -1.524 0.762)
			(end 1.524 0.762)
			(stroke
				(width 0.1524)
				(type default)
			)
			(layer "B.SilkS")
		)
		(fp_line
			(start 1.1049 -0.724916)
			(end 1.1049 0.724916)
			(stroke
				(width 0.1)
				(type default)
			)
			(layer "B.Fab")
		)
		(fp_line
			(start -1.1049 -0.724916)
			(end 1.1049 -0.724916)
			(stroke
				(width 0.1)
				(type default)
			)
			(layer "B.Fab")
		)
		(fp_line
			(start 1.1049 0.724916)
			(end -1.1049 0.724916)
			(stroke
				(width 0.1)
				(type default)
			)
			(layer "B.Fab")
		)
		(fp_line
			(start -1.1049 0.724916)
			(end -1.1049 -0.724916)
			(stroke
				(width 0.1)
				(type default)
			)
			(layer "B.Fab")
		)
		(pad "1" smd rect
			(at 0.889 0 90)
			(size 1.016 1.27)
			(layers "B.Cu" "B.Mask" "B.Paste")
			(net "SW_P12V_AUX_PVDDIO_P0_FLT")
		)
		(pad "2" smd rect
			(at -0.889 0 90)
			(size 1.016 1.27)
			(layers "B.Cu" "B.Mask" "B.Paste")
			(net "GND")
		)
	)
	(footprint ""
		(layer "B.Cu")
		(at 336.180684 -338.913216 -90)
		(property "Reference" "PC95_1"
			(at 0 0 90)
			(layer "B.SilkS")
			(hide yes)
			(effects
				(font
					(size 1.27 1.27)
				)
				(justify mirror)
			)
		)
		(property "Value" ""
			(at 0 0 90)
			(layer "B.Fab")
			(effects
				(font
					(size 1.27 1.27)
				)
				(justify mirror)
			)
		)
		(duplicate_pad_numbers_are_jumpers no)
		(fp_line
			(start -1.524 0.762)
			(end 1.524 0.762)
			(stroke
				(width 0.1524)
				(type default)
			)
			(layer "B.SilkS")
		)
		(fp_line
			(start 1.524 0.762)
			(end 1.524 -0.762)
			(stroke
				(width 0.1524)
				(type default)
			)
			(layer "B.SilkS")
		)
		(fp_line
			(start -1.524 -0.762)
			(end -1.524 0.762)
			(stroke
				(width 0.1524)
				(type default)
			)
			(layer "B.SilkS")
		)
		(fp_line
			(start 1.524 -0.762)
			(end -1.524 -0.762)
			(stroke
				(width 0.1524)
				(type default)
			)
			(layer "B.SilkS")
		)
		(fp_line
			(start -1.1049 0.724916)
			(end -1.1049 -0.724916)
			(stroke
				(width 0.1)
				(type default)
			)
			(layer "B.Fab")
		)
		(fp_line
			(start 1.1049 0.724916)
			(end -1.1049 0.724916)
			(stroke
				(width 0.1)
				(type default)
			)
			(layer "B.Fab")
		)
		(fp_line
			(start -1.1049 -0.724916)
			(end 1.1049 -0.724916)
			(stroke
				(width 0.1)
				(type default)
			)
			(layer "B.Fab")
		)
		(fp_line
			(start 1.1049 -0.724916)
			(end 1.1049 0.724916)
			(stroke
				(width 0.1)
				(type default)
			)
			(layer "B.Fab")
		)
		(pad "1" smd rect
			(at 0.889 0 270)
			(size 1.016 1.27)
			(layers "B.Cu" "B.Mask" "B.Paste")
			(net "SW_P12V_AUX_PVDDCR_CPU1_P0_FLT")
		)
		(pad "2" smd rect
			(at -0.889 0 270)
			(size 1.016 1.27)
			(layers "B.Cu" "B.Mask" "B.Paste")
			(net "GND")
		)
	)
	(footprint ""
		(layer "B.Cu")
		(at 382.618488 -396.393162 -90)
		(property "Reference" "C1012"
			(at 0 0 90)
			(layer "B.SilkS")
			(hide yes)
			(effects
				(font
					(size 1.27 1.27)
				)
				(justify mirror)
			)
		)
		(property "Value" ""
			(at 0 0 90)
			(layer "B.Fab")
			(effects
				(font
					(size 1.27 1.27)
				)
				(justify mirror)
			)
		)
		(duplicate_pad_numbers_are_jumpers no)
		(fp_line
			(start -0.299974 0.150114)
			(end 0.299974 0.150114)
			(stroke
				(width 0.1)
				(type default)
			)
			(layer "B.Fab")
		)
		(fp_line
			(start 0.299974 0.150114)
			(end 0.299974 -0.150114)
			(stroke
				(width 0.1)
				(type default)
			)
			(layer "B.Fab")
		)
		(fp_line
			(start -0.299974 -0.150114)
			(end -0.299974 0.150114)
			(stroke
				(width 0.1)
				(type default)
			)
			(layer "B.Fab")
		)
		(fp_line
			(start 0.299974 -0.150114)
			(end -0.299974 -0.150114)
			(stroke
				(width 0.1)
				(type default)
			)
			(layer "B.Fab")
		)
		(pad "1" smd rect
			(at 0.2667 0 90)
			(size 0.3048 0.381)
			(layers "B.Cu" "B.Mask" "B.Paste")
			(net "P0V9_CPU0_RT_2D")
		)
		(pad "2" smd rect
			(at -0.2667 0 90)
			(size 0.3048 0.381)
			(layers "B.Cu" "B.Mask" "B.Paste")
			(net "GND")
		)
	)
	(footprint ""
		(layer "B.Cu")
		(at 205.375256 -70.31228 180)
		(property "Reference" "R3214"
			(at 0 0 0)
			(layer "B.SilkS")
			(hide yes)
			(effects
				(font
					(size 1.27 1.27)
				)
				(justify mirror)
			)
		)
		(property "Value" ""
			(at 0 0 0)
			(layer "B.Fab")
			(effects
				(font
					(size 1.27 1.27)
				)
				(justify mirror)
			)
		)
		(duplicate_pad_numbers_are_jumpers no)
		(fp_line
			(start 0.7874 0.4064)
			(end 0.7874 -0.4064)
			(stroke
				(width 0.1524)
				(type default)
			)
			(layer "B.SilkS")
		)
		(fp_line
			(start 0.7874 -0.4064)
			(end -0.7874 -0.4064)
			(stroke
				(width 0.1524)
				(type default)
			)
			(layer "B.SilkS")
		)
		(fp_line
			(start -0.7874 0.4064)
			(end 0.7874 0.4064)
			(stroke
				(width 0.1524)
				(type default)
			)
			(layer "B.SilkS")
		)
		(fp_line
			(start -0.7874 -0.4064)
			(end -0.7874 0.4064)
			(stroke
				(width 0.1524)
				(type default)
			)
			(layer "B.SilkS")
		)
		(fp_line
			(start 0.67945 0.3048)
			(end 0.67945 -0.305054)
			(stroke
				(width 0.1)
				(type default)
			)
			(layer "B.Fab")
		)
		(fp_line
			(start 0.67945 -0.305054)
			(end 0.12065 -0.305054)
			(stroke
				(width 0.1)
				(type default)
			)
			(layer "B.Fab")
		)
		(fp_line
			(start 0.12065 0.3048)
			(end 0.67945 0.3048)
			(stroke
				(width 0.1)
				(type default)
			)
			(layer "B.Fab")
		)
		(fp_line
			(start 0.12065 0.2794)
			(end 0.12065 0.3048)
			(stroke
				(width 0.1)
				(type default)
			)
			(layer "B.Fab")
		)
		(fp_line
			(start 0.12065 -0.2794)
			(end -0.12065 -0.2794)
			(stroke
				(width 0.1)
				(type default)
			)
			(layer "B.Fab")
		)
		(fp_line
			(start 0.12065 -0.305054)
			(end 0.12065 -0.2794)
			(stroke
				(width 0.1)
				(type default)
			)
			(layer "B.Fab")
		)
		(fp_line
			(start -0.120396 0.3048)
			(end -0.120396 0.2794)
			(stroke
				(width 0.1)
				(type default)
			)
			(layer "B.Fab")
		)
		(fp_line
			(start -0.120396 0.2794)
			(end 0.12065 0.2794)
			(stroke
				(width 0.1)
				(type default)
			)
			(layer "B.Fab")
		)
		(fp_line
			(start -0.12065 -0.2794)
			(end -0.12065 -0.3048)
			(stroke
				(width 0.1)
				(type default)
			)
			(layer "B.Fab")
		)
		(fp_line
			(start -0.12065 -0.3048)
			(end -0.67945 -0.3048)
			(stroke
				(width 0.1)
				(type default)
			)
			(layer "B.Fab")
		)
		(fp_line
			(start -0.67945 0.3048)
			(end -0.120396 0.3048)
			(stroke
				(width 0.1)
				(type default)
			)
			(layer "B.Fab")
		)
		(fp_line
			(start -0.67945 -0.3048)
			(end -0.67945 0.3048)
			(stroke
				(width 0.1)
				(type default)
			)
			(layer "B.Fab")
		)
		(pad "1" smd circle
			(at 0.40005 0)
			(size 0 0)
			(layers "B.Cu" "B.Mask" "B.Paste")
			(net "NCSI_BMC_TXD0_R1")
		)
		(pad "2" smd circle
			(at -0.40005 0)
			(size 0 0)
			(layers "B.Cu" "B.Mask" "B.Paste")
			(net "RMII_BMC_OCP_TXD_0")
		)
	)
	(footprint ""
		(layer "B.Cu")
		(at 370.478558 -395.148562 90)
		(property "Reference" "C1017"
			(at 0 0 90)
			(layer "B.SilkS")
			(hide yes)
			(effects
				(font
					(size 1.27 1.27)
				)
				(justify mirror)
			)
		)
		(property "Value" ""
			(at 0 0 90)
			(layer "B.Fab")
			(effects
				(font
					(size 1.27 1.27)
				)
				(justify mirror)
			)
		)
		(duplicate_pad_numbers_are_jumpers no)
		(fp_line
			(start 0.299974 -0.150114)
			(end -0.299974 -0.150114)
			(stroke
				(width 0.1)
				(type default)
			)
			(layer "B.Fab")
		)
		(fp_line
			(start -0.299974 -0.150114)
			(end -0.299974 0.150114)
			(stroke
				(width 0.1)
				(type default)
			)
			(layer "B.Fab")
		)
		(fp_line
			(start 0.299974 0.150114)
			(end 0.299974 -0.150114)
			(stroke
				(width 0.1)
				(type default)
			)
			(layer "B.Fab")
		)
		(fp_line
			(start -0.299974 0.150114)
			(end 0.299974 0.150114)
			(stroke
				(width 0.1)
				(type default)
			)
			(layer "B.Fab")
		)
		(pad "1" smd rect
			(at 0.2667 0 270)
			(size 0.3048 0.381)
			(layers "B.Cu" "B.Mask" "B.Paste")
			(net "P0V9_CPU0_RT3_2A")
		)
		(pad "2" smd rect
			(at -0.2667 0 270)
			(size 0.3048 0.381)
			(layers "B.Cu" "B.Mask" "B.Paste")
			(net "GND")
		)
	)
	(footprint ""
		(layer "B.Cu")
		(at 243.713 -321.818)
		(property "Reference" "C1083"
			(at 0 0 0)
			(layer "B.SilkS")
			(hide yes)
			(effects
				(font
					(size 1.27 1.27)
				)
				(justify mirror)
			)
		)
		(property "Value" ""
			(at 0 0 0)
			(layer "B.Fab")
			(effects
				(font
					(size 1.27 1.27)
				)
				(justify mirror)
			)
		)
		(duplicate_pad_numbers_are_jumpers no)
		(fp_line
			(start -0.7874 -0.4064)
			(end -0.7874 0.4064)
			(stroke
				(width 0.1524)
				(type default)
			)
			(layer "B.SilkS")
		)
		(fp_line
			(start -0.7874 0.4064)
			(end 0.7874 0.4064)
			(stroke
				(width 0.1524)
				(type default)
			)
			(layer "B.SilkS")
		)
		(fp_line
			(start 0.7874 -0.4064)
			(end -0.7874 -0.4064)
			(stroke
				(width 0.1524)
				(type default)
			)
			(layer "B.SilkS")
		)
		(fp_line
			(start 0.7874 0.4064)
			(end 0.7874 -0.4064)
			(stroke
				(width 0.1524)
				(type default)
			)
			(layer "B.SilkS")
		)
		(fp_line
			(start -0.67945 -0.3048)
			(end -0.67945 0.3048)
			(stroke
				(width 0.1)
				(type default)
			)
			(layer "B.Fab")
		)
		(fp_line
			(start -0.67945 0.3048)
			(end -0.120396 0.3048)
			(stroke
				(width 0.1)
				(type default)
			)
			(layer "B.Fab")
		)
		(fp_line
			(start -0.12065 -0.3048)
			(end -0.67945 -0.3048)
			(stroke
				(width 0.1)
				(type default)
			)
			(layer "B.Fab")
		)
		(fp_line
			(start -0.12065 -0.2794)
			(end -0.12065 -0.3048)
			(stroke
				(width 0.1)
				(type default)
			)
			(layer "B.Fab")
		)
		(fp_line
			(start -0.120396 0.2794)
			(end 0.12065 0.2794)
			(stroke
				(width 0.1)
				(type default)
			)
			(layer "B.Fab")
		)
		(fp_line
			(start -0.120396 0.3048)
			(end -0.120396 0.2794)
			(stroke
				(width 0.1)
				(type default)
			)
			(layer "B.Fab")
		)
		(fp_line
			(start 0.12065 -0.305054)
			(end 0.12065 -0.2794)
			(stroke
				(width 0.1)
				(type default)
			)
			(layer "B.Fab")
		)
		(fp_line
			(start 0.12065 -0.2794)
			(end -0.12065 -0.2794)
			(stroke
				(width 0.1)
				(type default)
			)
			(layer "B.Fab")
		)
		(fp_line
			(start 0.12065 0.2794)
			(end 0.12065 0.3048)
			(stroke
				(width 0.1)
				(type default)
			)
			(layer "B.Fab")
		)
		(fp_line
			(start 0.12065 0.3048)
			(end 0.67945 0.3048)
			(stroke
				(width 0.1)
				(type default)
			)
			(layer "B.Fab")
		)
		(fp_line
			(start 0.67945 -0.305054)
			(end 0.12065 -0.305054)
			(stroke
				(width 0.1)
				(type default)
			)
			(layer "B.Fab")
		)
		(fp_line
			(start 0.67945 0.3048)
			(end 0.67945 -0.305054)
			(stroke
				(width 0.1)
				(type default)
			)
			(layer "B.Fab")
		)
		(pad "1" smd circle
			(at 0.40005 0 180)
			(size 0 0)
			(layers "B.Cu" "B.Mask" "B.Paste")
			(net "P1V8_CPU1_RT_1D_ADC_MAM")
		)
		(pad "2" smd circle
			(at -0.40005 0 180)
			(size 0 0)
			(layers "B.Cu" "B.Mask" "B.Paste")
			(net "GND")
		)
	)
	(footprint ""
		(layer "B.Cu")
		(at 314.178188 -395.148562 90)
		(property "Reference" "C513"
			(at 0 0 90)
			(layer "B.SilkS")
			(hide yes)
			(effects
				(font
					(size 1.27 1.27)
				)
				(justify mirror)
			)
		)
		(property "Value" ""
			(at 0 0 90)
			(layer "B.Fab")
			(effects
				(font
					(size 1.27 1.27)
				)
				(justify mirror)
			)
		)
		(duplicate_pad_numbers_are_jumpers no)
		(fp_line
			(start 0.299974 -0.150114)
			(end -0.299974 -0.150114)
			(stroke
				(width 0.1)
				(type default)
			)
			(layer "B.Fab")
		)
		(fp_line
			(start -0.299974 -0.150114)
			(end -0.299974 0.150114)
			(stroke
				(width 0.1)
				(type default)
			)
			(layer "B.Fab")
		)
		(fp_line
			(start 0.299974 0.150114)
			(end 0.299974 -0.150114)
			(stroke
				(width 0.1)
				(type default)
			)
			(layer "B.Fab")
		)
		(fp_line
			(start -0.299974 0.150114)
			(end 0.299974 0.150114)
			(stroke
				(width 0.1)
				(type default)
			)
			(layer "B.Fab")
		)
		(pad "1" smd rect
			(at 0.2667 0 270)
			(size 0.3048 0.381)
			(layers "B.Cu" "B.Mask" "B.Paste")
			(net "P1V8_CPU0_RT0_1A_1D")
		)
		(pad "2" smd rect
			(at -0.2667 0 270)
			(size 0.3048 0.381)
			(layers "B.Cu" "B.Mask" "B.Paste")
			(net "GND")
		)
	)
)
